# SCM (Grand Teton) — schematic netlist excerpt (pin names and nets, part order shuffled) for the footprints in the layout excerpt that follows; sources: Cadence DE-HDL packaged netlist, KiCad conversion of 12092022_DA0F0TMDCD0_F0T_Management_Board_D_brd_V3_OCP.brd

R824  Q_RES  33.2 1% CHIP  pkg 0402LF  page 13 : A = FM_VIRTUAL_RESEAT ; B = FM_VIRTUAL_RESEAT_BMC
R174  Q_RES  33.2 1% CHIP  pkg 0402LF  page 44 : A = SPI_BMC_BIOS_ROM_CLK ; B = SPI_BMC_BIOS_ROM_R_CLK

(kicad_pcb
	(version 20260206)
	(generator "pcbnew")
	(generator_version "10.0")
	(general
		(thickness 1.6)
		(legacy_teardrops no)
	)
	(paper "A4")
	(title_block
		(title "12092022_DA0F0TMDCD0_F0T_Management_Board_D_brd_V3_OCP.brd")
		(comment 1 "Grand Teton / footprints 303-304 of 1440")
	)
	(layers
		(0 "F.Cu" signal "TOP")
		(4 "In1.Cu" signal "GND")
		(6 "In2.Cu" signal "IN1")
		(8 "In3.Cu" signal "GND1")
		(10 "In4.Cu" signal "IN2")
		(12 "In5.Cu" signal "VCC")
		(14 "In6.Cu" signal "VCC1")
		(16 "In7.Cu" signal "IN3")
		(18 "In8.Cu" signal "GND2")
		(20 "In9.Cu" signal "IN4")
		(22 "In10.Cu" signal "GND3")
		(2 "B.Cu" signal "BOTTOM")
		(9 "F.Adhes" user "F.Adhesive")
		(11 "B.Adhes" user "B.Adhesive")
		(13 "F.Paste" user "Package Geometry/Pastemask Top")
		(15 "B.Paste" user "Package Geometry/Pastemask Bottom")
		(5 "F.SilkS" user "Ref Des/Silkscreen Top")
		(7 "B.SilkS" user "Ref Des/Silkscreen Bottom")
		(1 "F.Mask" user "Board Geometry/Soldermask Top")
		(3 "B.Mask" user "Board Geometry/Soldermask Bottom")
		(17 "Dwgs.User" user "User.Drawings")
		(19 "Cmts.User" user "User.Comments")
		(21 "Eco1.User" user "User.Eco1")
		(23 "Eco2.User" user "User.Eco2")
		(25 "Edge.Cuts" user "Board Geometry/Outline")
		(27 "Margin" user)
		(31 "F.CrtYd" user "Package Geometry/Place Bound Top")
		(29 "B.CrtYd" user "Package Geometry/Place Bound Bottom")
		(35 "F.Fab" user "Ref Des/Assembly Top")
		(33 "B.Fab" user "Ref Des/Assembly Bottom")
	)
	(footprint ""
		(layer "F.Cu")
		(at 67.818 -106.2736 -90)
		(property "Reference" "R824"
			(at 0 0 270)
			(layer "F.SilkS")
			(hide yes)
			(effects
				(font
					(size 1.27 1.27)
				)
			)
		)
		(property "Value" ""
			(at 0 0 270)
			(layer "F.Fab")
			(effects
				(font
					(size 1.27 1.27)
				)
			)
		)
		(duplicate_pad_numbers_are_jumpers no)
		(fp_line
			(start -0.7874 0.4064)
			(end -0.7874 -0.4064)
			(stroke
				(width 0.1524)
				(type default)
			)
			(layer "F.SilkS")
		)
		(fp_line
			(start 0.7874 0.4064)
			(end -0.7874 0.4064)
			(stroke
				(width 0.1524)
				(type default)
			)
			(layer "F.SilkS")
		)
		(fp_line
			(start -0.7874 -0.4064)
			(end 0.7874 -0.4064)
			(stroke
				(width 0.1524)
				(type default)
			)
			(layer "F.SilkS")
		)
		(fp_line
			(start 0.7874 -0.4064)
			(end 0.7874 0.4064)
			(stroke
				(width 0.1524)
				(type default)
			)
			(layer "F.SilkS")
		)
		(fp_line
			(start -0.67945 0.3048)
			(end -0.67945 -0.305054)
			(stroke
				(width 0.1)
				(type default)
			)
			(layer "F.Fab")
		)
		(fp_line
			(start -0.12065 0.3048)
			(end -0.67945 0.3048)
			(stroke
				(width 0.1)
				(type default)
			)
			(layer "F.Fab")
		)
		(fp_line
			(start 0.120396 0.3048)
			(end 0.120396 0.2794)
			(stroke
				(width 0.1)
				(type default)
			)
			(layer "F.Fab")
		)
		(fp_line
			(start 0.67945 0.3048)
			(end 0.120396 0.3048)
			(stroke
				(width 0.1)
				(type default)
			)
			(layer "F.Fab")
		)
		(fp_line
			(start -0.12065 0.2794)
			(end -0.12065 0.3048)
			(stroke
				(width 0.1)
				(type default)
			)
			(layer "F.Fab")
		)
		(fp_line
			(start 0.120396 0.2794)
			(end -0.12065 0.2794)
			(stroke
				(width 0.1)
				(type default)
			)
			(layer "F.Fab")
		)
		(fp_line
			(start -0.12065 -0.2794)
			(end 0.12065 -0.2794)
			(stroke
				(width 0.1)
				(type default)
			)
			(layer "F.Fab")
		)
		(fp_line
			(start 0.12065 -0.2794)
			(end 0.12065 -0.3048)
			(stroke
				(width 0.1)
				(type default)
			)
			(layer "F.Fab")
		)
		(fp_line
			(start 0.12065 -0.3048)
			(end 0.67945 -0.3048)
			(stroke
				(width 0.1)
				(type default)
			)
			(layer "F.Fab")
		)
		(fp_line
			(start 0.67945 -0.3048)
			(end 0.67945 0.3048)
			(stroke
				(width 0.1)
				(type default)
			)
			(layer "F.Fab")
		)
		(fp_line
			(start -0.67945 -0.305054)
			(end -0.12065 -0.305054)
			(stroke
				(width 0.1)
				(type default)
			)
			(layer "F.Fab")
		)
		(fp_line
			(start -0.12065 -0.305054)
			(end -0.12065 -0.2794)
			(stroke
				(width 0.1)
				(type default)
			)
			(layer "F.Fab")
		)
		(pad "1" smd circle
			(at -0.40005 0 270)
			(size 0 0)
			(layers "F.Cu" "F.Mask" "F.Paste")
			(net "FM_VIRTUAL_RESEAT")
		)
		(pad "2" smd circle
			(at 0.40005 0 270)
			(size 0 0)
			(layers "F.Cu" "F.Mask" "F.Paste")
			(net "FM_VIRTUAL_RESEAT_BMC")
		)
	)
	(footprint ""
		(layer "F.Cu")
		(at 60.7314 -64.0588 90)
		(property "Reference" "R174"
			(at 0 0 90)
			(layer "F.SilkS")
			(hide yes)
			(effects
				(font
					(size 1.27 1.27)
				)
			)
		)
		(property "Value" ""
			(at 0 0 90)
			(layer "F.Fab")
			(effects
				(font
					(size 1.27 1.27)
				)
			)
		)
		(duplicate_pad_numbers_are_jumpers no)
		(fp_line
			(start 0.7874 -0.4064)
			(end 0.7874 0.4064)
			(stroke
				(width 0.1524)
				(type default)
			)
			(layer "F.SilkS")
		)
		(fp_line
			(start -0.7874 -0.4064)
			(end 0.7874 -0.4064)
			(stroke
				(width 0.1524)
				(type default)
			)
			(layer "F.SilkS")
		)
		(fp_line
			(start 0.7874 0.4064)
			(end -0.7874 0.4064)
			(stroke
				(width 0.1524)
				(type default)
			)
			(layer "F.SilkS")
		)
		(fp_line
			(start -0.7874 0.4064)
			(end -0.7874 -0.4064)
			(stroke
				(width 0.1524)
				(type default)
			)
			(layer "F.SilkS")
		)
		(fp_line
			(start -0.12065 -0.305054)
			(end -0.12065 -0.2794)
			(stroke
				(width 0.1)
				(type default)
			)
			(layer "F.Fab")
		)
		(fp_line
			(start -0.67945 -0.305054)
			(end -0.12065 -0.305054)
			(stroke
				(width 0.1)
				(type default)
			)
			(layer "F.Fab")
		)
		(fp_line
			(start 0.67945 -0.3048)
			(end 0.67945 0.3048)
			(stroke
				(width 0.1)
				(type default)
			)
			(layer "F.Fab")
		)
		(fp_line
			(start 0.12065 -0.3048)
			(end 0.67945 -0.3048)
			(stroke
				(width 0.1)
				(type default)
			)
			(layer "F.Fab")
		)
		(fp_line
			(start 0.12065 -0.2794)
			(end 0.12065 -0.3048)
			(stroke
				(width 0.1)
				(type default)
			)
			(layer "F.Fab")
		)
		(fp_line
			(start -0.12065 -0.2794)
			(end 0.12065 -0.2794)
			(stroke
				(width 0.1)
				(type default)
			)
			(layer "F.Fab")
		)
		(fp_line
			(start 0.120396 0.2794)
			(end -0.12065 0.2794)
			(stroke
				(width 0.1)
				(type default)
			)
			(layer "F.Fab")
		)
		(fp_line
			(start -0.12065 0.2794)
			(end -0.12065 0.3048)
			(stroke
				(width 0.1)
				(type default)
			)
			(layer "F.Fab")
		)
		(fp_line
			(start 0.67945 0.3048)
			(end 0.120396 0.3048)
			(stroke
				(width 0.1)
				(type default)
			)
			(layer "F.Fab")
		)
		(fp_line
			(start 0.120396 0.3048)
			(end 0.120396 0.2794)
			(stroke
				(width 0.1)
				(type default)
			)
			(layer "F.Fab")
		)
		(fp_line
			(start -0.12065 0.3048)
			(end -0.67945 0.3048)
			(stroke
				(width 0.1)
				(type default)
			)
			(layer "F.Fab")
		)
		(fp_line
			(start -0.67945 0.3048)
			(end -0.67945 -0.305054)
			(stroke
				(width 0.1)
				(type default)
			)
			(layer "F.Fab")
		)
		(pad "1" smd circle
			(at -0.40005 0 90)
			(size 0 0)
			(layers "F.Cu" "F.Mask" "F.Paste")
			(net "SPI_BMC_BIOS_ROM_CLK")
		)
		(pad "2" smd circle
			(at 0.40005 0 90)
			(size 0 0)
			(layers "F.Cu" "F.Mask" "F.Paste")
			(net "SPI_BMC_BIOS_ROM_R_CLK")
		)
	)
)
